# S9S_MB_2U (Grand Teton) — schematic netlist excerpt (pin names and nets, part order shuffled) for the footprints in the layout excerpt that follows; sources: Cadence DE-HDL packaged netlist, KiCad conversion of 03242023_DA0F0TMBIJ0_F0T_Motherboard_J_brd_V01_OCP.brd

C1563  Q_CAP_DIFFBUS  DIFF BUS_0.22UF 6.3V 20% X6S  pkg C0201  page 175 : \1\ = P5E_CPU0_PE4_TX_C_DP<8> ; \2\ = P5E_CPU0_PE4_TX_DP<8>
PC1222  Q_CAP  0.22UF 25V 10% X7R  pkg C0402  page 262 : A = SW_P1V05_PCH_AUX_BST ; B = SW_P1V05_PCH_AUX_SW
R274  Q_RES  10K 1% CHIP  pkg 0402LF  page 119 : A = P3V3_AUX ; B = FM_CPU1_PROC_ID1

(kicad_pcb
	(version 20260206)
	(generator "pcbnew")
	(generator_version "10.0")
	(general
		(thickness 1.6)
		(legacy_teardrops no)
	)
	(paper "A4")
	(title_block
		(title "03242023_DA0F0TMBIJ0_F0T_Motherboard_J_brd_V01_OCP.brd")
		(comment 1 "Grand Teton / footprints 2255-2257 of 6105")
	)
	(layers
		(0 "F.Cu" signal "TOP")
		(4 "In1.Cu" signal "GND")
		(6 "In2.Cu" signal "IN1")
		(8 "In3.Cu" signal "GND1")
		(10 "In4.Cu" signal "IN2")
		(12 "In5.Cu" signal "GND2")
		(14 "In6.Cu" signal "IN3")
		(16 "In7.Cu" signal "GND3")
		(18 "In8.Cu" signal "VCC")
		(20 "In9.Cu" signal "VCC1")
		(22 "In10.Cu" signal "GND4")
		(24 "In11.Cu" signal "IN4")
		(26 "In12.Cu" signal "GND5")
		(28 "In13.Cu" signal "IN5")
		(30 "In14.Cu" signal "GND6")
		(32 "In15.Cu" signal "IN6")
		(34 "In16.Cu" signal "GND7")
		(2 "B.Cu" signal "BOTTOM")
		(9 "F.Adhes" user "F.Adhesive")
		(11 "B.Adhes" user "B.Adhesive")
		(13 "F.Paste" user "Package Geometry/Pastemask Top")
		(15 "B.Paste" user "Package Geometry/Pastemask Bottom")
		(5 "F.SilkS" user "Ref Des/Silkscreen Top")
		(7 "B.SilkS" user "Ref Des/Silkscreen Bottom")
		(1 "F.Mask" user "Board Geometry/Soldermask Top")
		(3 "B.Mask" user "Board Geometry/Soldermask Bottom")
		(17 "Dwgs.User" user "User.Drawings")
		(19 "Cmts.User" user "User.Comments")
		(21 "Eco1.User" user "User.Eco1")
		(23 "Eco2.User" user "User.Eco2")
		(25 "Edge.Cuts" user "Board Geometry/Outline")
		(27 "Margin" user)
		(31 "F.CrtYd" user "Package Geometry/Place Bound Top")
		(29 "B.CrtYd" user "Package Geometry/Place Bound Bottom")
		(35 "F.Fab" user "Ref Des/Assembly Top")
		(33 "B.Fab" user "Ref Des/Assembly Bottom")
	)
	(footprint ""
		(layer "F.Cu")
		(at 264.801858 -73.94067)
		(property "Reference" "PC1222"
			(at 0 0 0)
			(layer "F.SilkS")
			(hide yes)
			(effects
				(font
					(size 1.27 1.27)
				)
			)
		)
		(property "Value" ""
			(at 0 0 0)
			(layer "F.Fab")
			(effects
				(font
					(size 1.27 1.27)
				)
			)
		)
		(duplicate_pad_numbers_are_jumpers no)
		(fp_line
			(start -0.7874 -0.4064)
			(end 0.7874 -0.4064)
			(stroke
				(width 0.1524)
				(type default)
			)
			(layer "F.SilkS")
		)
		(fp_line
			(start -0.7874 0.4064)
			(end -0.7874 -0.4064)
			(stroke
				(width 0.1524)
				(type default)
			)
			(layer "F.SilkS")
		)
		(fp_line
			(start 0.7874 -0.4064)
			(end 0.7874 0.4064)
			(stroke
				(width 0.1524)
				(type default)
			)
			(layer "F.SilkS")
		)
		(fp_line
			(start 0.7874 0.4064)
			(end -0.7874 0.4064)
			(stroke
				(width 0.1524)
				(type default)
			)
			(layer "F.SilkS")
		)
		(fp_line
			(start -0.67945 -0.305054)
			(end -0.12065 -0.305054)
			(stroke
				(width 0.1)
				(type default)
			)
			(layer "F.Fab")
		)
		(fp_line
			(start -0.67945 0.3048)
			(end -0.67945 -0.305054)
			(stroke
				(width 0.1)
				(type default)
			)
			(layer "F.Fab")
		)
		(fp_line
			(start -0.12065 -0.305054)
			(end -0.12065 -0.2794)
			(stroke
				(width 0.1)
				(type default)
			)
			(layer "F.Fab")
		)
		(fp_line
			(start -0.12065 -0.2794)
			(end 0.12065 -0.2794)
			(stroke
				(width 0.1)
				(type default)
			)
			(layer "F.Fab")
		)
		(fp_line
			(start -0.12065 0.2794)
			(end -0.12065 0.3048)
			(stroke
				(width 0.1)
				(type default)
			)
			(layer "F.Fab")
		)
		(fp_line
			(start -0.12065 0.3048)
			(end -0.67945 0.3048)
			(stroke
				(width 0.1)
				(type default)
			)
			(layer "F.Fab")
		)
		(fp_line
			(start 0.120396 0.2794)
			(end -0.12065 0.2794)
			(stroke
				(width 0.1)
				(type default)
			)
			(layer "F.Fab")
		)
		(fp_line
			(start 0.120396 0.3048)
			(end 0.120396 0.2794)
			(stroke
				(width 0.1)
				(type default)
			)
			(layer "F.Fab")
		)
		(fp_line
			(start 0.12065 -0.3048)
			(end 0.67945 -0.3048)
			(stroke
				(width 0.1)
				(type default)
			)
			(layer "F.Fab")
		)
		(fp_line
			(start 0.12065 -0.2794)
			(end 0.12065 -0.3048)
			(stroke
				(width 0.1)
				(type default)
			)
			(layer "F.Fab")
		)
		(fp_line
			(start 0.67945 -0.3048)
			(end 0.67945 0.3048)
			(stroke
				(width 0.1)
				(type default)
			)
			(layer "F.Fab")
		)
		(fp_line
			(start 0.67945 0.3048)
			(end 0.120396 0.3048)
			(stroke
				(width 0.1)
				(type default)
			)
			(layer "F.Fab")
		)
		(pad "1" smd circle
			(at -0.40005 0)
			(size 0 0)
			(layers "F.Cu" "F.Mask" "F.Paste")
			(net "SW_P1V05_PCH_AUX_BST")
		)
		(pad "2" smd circle
			(at 0.40005 0)
			(size 0 0)
			(layers "F.Cu" "F.Mask" "F.Paste")
			(net "SW_P1V05_PCH_AUX_SW")
		)
	)
	(footprint ""
		(layer "F.Cu")
		(at 182.17388 -126.964948 -90)
		(property "Reference" "R274"
			(at 0 0 270)
			(layer "F.SilkS")
			(hide yes)
			(effects
				(font
					(size 1.27 1.27)
				)
			)
		)
		(property "Value" ""
			(at 0 0 270)
			(layer "F.Fab")
			(effects
				(font
					(size 1.27 1.27)
				)
			)
		)
		(duplicate_pad_numbers_are_jumpers no)
		(fp_line
			(start -0.7874 0.4064)
			(end -0.7874 -0.4064)
			(stroke
				(width 0.1524)
				(type default)
			)
			(layer "F.SilkS")
		)
		(fp_line
			(start 0.7874 0.4064)
			(end -0.7874 0.4064)
			(stroke
				(width 0.1524)
				(type default)
			)
			(layer "F.SilkS")
		)
		(fp_line
			(start -0.7874 -0.4064)
			(end 0.7874 -0.4064)
			(stroke
				(width 0.1524)
				(type default)
			)
			(layer "F.SilkS")
		)
		(fp_line
			(start 0.7874 -0.4064)
			(end 0.7874 0.4064)
			(stroke
				(width 0.1524)
				(type default)
			)
			(layer "F.SilkS")
		)
		(fp_line
			(start -0.67945 0.3048)
			(end -0.67945 -0.305054)
			(stroke
				(width 0.1)
				(type default)
			)
			(layer "F.Fab")
		)
		(fp_line
			(start -0.12065 0.3048)
			(end -0.67945 0.3048)
			(stroke
				(width 0.1)
				(type default)
			)
			(layer "F.Fab")
		)
		(fp_line
			(start 0.120396 0.3048)
			(end 0.120396 0.2794)
			(stroke
				(width 0.1)
				(type default)
			)
			(layer "F.Fab")
		)
		(fp_line
			(start 0.67945 0.3048)
			(end 0.120396 0.3048)
			(stroke
				(width 0.1)
				(type default)
			)
			(layer "F.Fab")
		)
		(fp_line
			(start -0.12065 0.2794)
			(end -0.12065 0.3048)
			(stroke
				(width 0.1)
				(type default)
			)
			(layer "F.Fab")
		)
		(fp_line
			(start 0.120396 0.2794)
			(end -0.12065 0.2794)
			(stroke
				(width 0.1)
				(type default)
			)
			(layer "F.Fab")
		)
		(fp_line
			(start -0.12065 -0.2794)
			(end 0.12065 -0.2794)
			(stroke
				(width 0.1)
				(type default)
			)
			(layer "F.Fab")
		)
		(fp_line
			(start 0.12065 -0.2794)
			(end 0.12065 -0.3048)
			(stroke
				(width 0.1)
				(type default)
			)
			(layer "F.Fab")
		)
		(fp_line
			(start 0.12065 -0.3048)
			(end 0.67945 -0.3048)
			(stroke
				(width 0.1)
				(type default)
			)
			(layer "F.Fab")
		)
		(fp_line
			(start 0.67945 -0.3048)
			(end 0.67945 0.3048)
			(stroke
				(width 0.1)
				(type default)
			)
			(layer "F.Fab")
		)
		(fp_line
			(start -0.67945 -0.305054)
			(end -0.12065 -0.305054)
			(stroke
				(width 0.1)
				(type default)
			)
			(layer "F.Fab")
		)
		(fp_line
			(start -0.12065 -0.305054)
			(end -0.12065 -0.2794)
			(stroke
				(width 0.1)
				(type default)
			)
			(layer "F.Fab")
		)
		(pad "1" smd circle
			(at -0.40005 0 270)
			(size 0 0)
			(layers "F.Cu" "F.Mask" "F.Paste")
			(net "P3V3_AUX")
		)
		(pad "2" smd circle
			(at 0.40005 0 270)
			(size 0 0)
			(layers "F.Cu" "F.Mask" "F.Paste")
			(net "FM_CPU1_PROC_ID1")
		)
	)
	(footprint ""
		(layer "F.Cu")
		(at 329.375008 -402.371052 -90)
		(property "Reference" "C1563"
			(at 0 0 270)
			(layer "F.SilkS")
			(hide yes)
			(effects
				(font
					(size 1.27 1.27)
				)
			)
		)
		(property "Value" ""
			(at 0 0 270)
			(layer "F.Fab")
			(effects
				(font
					(size 1.27 1.27)
				)
			)
		)
		(duplicate_pad_numbers_are_jumpers no)
		(fp_line
			(start -0.299974 0.150114)
			(end -0.299974 -0.150114)
			(stroke
				(width 0.1)
				(type default)
			)
			(layer "F.Fab")
		)
		(fp_line
			(start 0.299974 0.150114)
			(end -0.299974 0.150114)
			(stroke
				(width 0.1)
				(type default)
			)
			(layer "F.Fab")
		)
		(fp_line
			(start -0.299974 -0.150114)
			(end 0.299974 -0.150114)
			(stroke
				(width 0.1)
				(type default)
			)
			(layer "F.Fab")
		)
		(fp_line
			(start 0.299974 -0.150114)
			(end 0.299974 0.150114)
			(stroke
				(width 0.1)
				(type default)
			)
			(layer "F.Fab")
		)
		(pad "1" smd rect
			(at -0.2667 0 270)
			(size 0.3048 0.381)
			(layers "F.Cu" "F.Mask" "F.Paste")
			(net "P5E_CPU0_PE4_TX_C_DP<8>")
		)
		(pad "2" smd rect
			(at 0.2667 0 270)
			(size 0.3048 0.381)
			(layers "F.Cu" "F.Mask" "F.Paste")
			(net "P5E_CPU0_PE4_TX_DP<8>")
		)
	)
)
